# T6G (Grand Teton) — schematic netlist excerpt (pin names and nets, part order shuffled) for the footprints in the layout excerpt that follows; sources: Cadence DE-HDL packaged netlist, KiCad conversion of 04192023_DAF0TMB3IC0_F0TG_MB_C_brd_V02_OCP.brd

PR496  Q_RES  1.5 1% EMPTY  pkg 0402LF  page 194 : A = SW_PVDDCR_CPU0_P0_SW2_RC ; B = GND
PC2160  Q_CAP  0.1UF 25V 10% X7R  pkg 0402  page 135 : A = P12V_OCP_SFF ; B = GND
C770  Q_CAP_DIFFBUS  DIFF BUS_0.22UF 6.3V 20% X6S  pkg C0201  page 66 : \1\ = P5E_CPU1_P2_TX_C_DN<1> ; \2\ = P5E_CPU1_P2_TX_DN<1>

(kicad_pcb
	(version 20260206)
	(generator "pcbnew")
	(generator_version "10.0")
	(general
		(thickness 1.6)
		(legacy_teardrops no)
	)
	(paper "A4")
	(title_block
		(title "04192023_DAF0TMB3IC0_F0TG_MB_C_brd_V02_OCP.brd")
		(comment 1 "Grand Teton / footprints 1462-1464 of 8354")
	)
	(layers
		(0 "F.Cu" signal "TOP")
		(4 "In1.Cu" signal "GND")
		(6 "In2.Cu" signal "IN1")
		(8 "In3.Cu" signal "GND1")
		(10 "In4.Cu" signal "IN2")
		(12 "In5.Cu" signal "GND2")
		(14 "In6.Cu" signal "IN3")
		(16 "In7.Cu" signal "GND3")
		(18 "In8.Cu" signal "VCC")
		(20 "In9.Cu" signal "VCC1")
		(22 "In10.Cu" signal "GND4")
		(24 "In11.Cu" signal "IN4")
		(26 "In12.Cu" signal "GND5")
		(28 "In13.Cu" signal "IN5")
		(30 "In14.Cu" signal "GND6")
		(32 "In15.Cu" signal "IN6")
		(34 "In16.Cu" signal "GND7")
		(2 "B.Cu" signal "BOTTOM")
		(9 "F.Adhes" user "F.Adhesive")
		(11 "B.Adhes" user "B.Adhesive")
		(13 "F.Paste" user "Package Geometry/Pastemask Top")
		(15 "B.Paste" user "Package Geometry/Pastemask Bottom")
		(5 "F.SilkS" user "Ref Des/Silkscreen Top")
		(7 "B.SilkS" user "Ref Des/Silkscreen Bottom")
		(1 "F.Mask" user "Board Geometry/Soldermask Top")
		(3 "B.Mask" user "Board Geometry/Soldermask Bottom")
		(17 "Dwgs.User" user "User.Drawings")
		(19 "Cmts.User" user "User.Comments")
		(21 "Eco1.User" user "User.Eco1")
		(23 "Eco2.User" user "User.Eco2")
		(25 "Edge.Cuts" user "Board Geometry/Outline")
		(27 "Margin" user)
		(31 "F.CrtYd" user "Package Geometry/Place Bound Top")
		(29 "B.CrtYd" user "Package Geometry/Place Bound Bottom")
		(35 "F.Fab" user "Ref Des/Assembly Top")
		(33 "B.Fab" user "Ref Des/Assembly Bottom")
	)
	(footprint ""
		(layer "F.Cu")
		(at 376.352308 -184.478168 -90)
		(property "Reference" "PR496"
			(at 0 0 270)
			(layer "F.SilkS")
			(hide yes)
			(effects
				(font
					(size 1.27 1.27)
				)
			)
		)
		(property "Value" ""
			(at 0 0 270)
			(layer "F.Fab")
			(effects
				(font
					(size 1.27 1.27)
				)
			)
		)
		(duplicate_pad_numbers_are_jumpers no)
		(fp_line
			(start -0.7874 0.4064)
			(end -0.7874 -0.4064)
			(stroke
				(width 0.1524)
				(type default)
			)
			(layer "F.SilkS")
		)
		(fp_line
			(start 0.7874 0.4064)
			(end -0.7874 0.4064)
			(stroke
				(width 0.1524)
				(type default)
			)
			(layer "F.SilkS")
		)
		(fp_line
			(start -0.7874 -0.4064)
			(end 0.7874 -0.4064)
			(stroke
				(width 0.1524)
				(type default)
			)
			(layer "F.SilkS")
		)
		(fp_line
			(start 0.7874 -0.4064)
			(end 0.7874 0.4064)
			(stroke
				(width 0.1524)
				(type default)
			)
			(layer "F.SilkS")
		)
		(fp_line
			(start -0.67945 0.3048)
			(end -0.67945 -0.305054)
			(stroke
				(width 0.1)
				(type default)
			)
			(layer "F.Fab")
		)
		(fp_line
			(start -0.12065 0.3048)
			(end -0.67945 0.3048)
			(stroke
				(width 0.1)
				(type default)
			)
			(layer "F.Fab")
		)
		(fp_line
			(start 0.120396 0.3048)
			(end 0.120396 0.2794)
			(stroke
				(width 0.1)
				(type default)
			)
			(layer "F.Fab")
		)
		(fp_line
			(start 0.67945 0.3048)
			(end 0.120396 0.3048)
			(stroke
				(width 0.1)
				(type default)
			)
			(layer "F.Fab")
		)
		(fp_line
			(start -0.12065 0.2794)
			(end -0.12065 0.3048)
			(stroke
				(width 0.1)
				(type default)
			)
			(layer "F.Fab")
		)
		(fp_line
			(start 0.120396 0.2794)
			(end -0.12065 0.2794)
			(stroke
				(width 0.1)
				(type default)
			)
			(layer "F.Fab")
		)
		(fp_line
			(start -0.12065 -0.2794)
			(end 0.12065 -0.2794)
			(stroke
				(width 0.1)
				(type default)
			)
			(layer "F.Fab")
		)
		(fp_line
			(start 0.12065 -0.2794)
			(end 0.12065 -0.3048)
			(stroke
				(width 0.1)
				(type default)
			)
			(layer "F.Fab")
		)
		(fp_line
			(start 0.12065 -0.3048)
			(end 0.67945 -0.3048)
			(stroke
				(width 0.1)
				(type default)
			)
			(layer "F.Fab")
		)
		(fp_line
			(start 0.67945 -0.3048)
			(end 0.67945 0.3048)
			(stroke
				(width 0.1)
				(type default)
			)
			(layer "F.Fab")
		)
		(fp_line
			(start -0.67945 -0.305054)
			(end -0.12065 -0.305054)
			(stroke
				(width 0.1)
				(type default)
			)
			(layer "F.Fab")
		)
		(fp_line
			(start -0.12065 -0.305054)
			(end -0.12065 -0.2794)
			(stroke
				(width 0.1)
				(type default)
			)
			(layer "F.Fab")
		)
		(pad "1" smd circle
			(at -0.40005 0 270)
			(size 0 0)
			(layers "F.Cu" "F.Mask" "F.Paste")
			(net "SW_PVDDCR_CPU0_P0_SW2_RC")
		)
		(pad "2" smd circle
			(at 0.40005 0 270)
			(size 0 0)
			(layers "F.Cu" "F.Mask" "F.Paste")
			(net "GND")
		)
	)
	(footprint ""
		(layer "F.Cu")
		(at 142.595092 -376.85726 180)
		(property "Reference" "C770"
			(at 0 0 180)
			(layer "F.SilkS")
			(hide yes)
			(effects
				(font
					(size 1.27 1.27)
				)
			)
		)
		(property "Value" ""
			(at 0 0 180)
			(layer "F.Fab")
			(effects
				(font
					(size 1.27 1.27)
				)
			)
		)
		(duplicate_pad_numbers_are_jumpers no)
		(fp_line
			(start 0.299974 0.150114)
			(end -0.299974 0.150114)
			(stroke
				(width 0.1)
				(type default)
			)
			(layer "F.Fab")
		)
		(fp_line
			(start 0.299974 -0.150114)
			(end 0.299974 0.150114)
			(stroke
				(width 0.1)
				(type default)
			)
			(layer "F.Fab")
		)
		(fp_line
			(start -0.299974 0.150114)
			(end -0.299974 -0.150114)
			(stroke
				(width 0.1)
				(type default)
			)
			(layer "F.Fab")
		)
		(fp_line
			(start -0.299974 -0.150114)
			(end 0.299974 -0.150114)
			(stroke
				(width 0.1)
				(type default)
			)
			(layer "F.Fab")
		)
		(pad "1" smd rect
			(at -0.2667 0 180)
			(size 0.3048 0.381)
			(layers "F.Cu" "F.Mask" "F.Paste")
			(net "P5E_CPU1_P2_TX_C_DN<1>")
		)
		(pad "2" smd rect
			(at 0.2667 0 180)
			(size 0.3048 0.381)
			(layers "F.Cu" "F.Mask" "F.Paste")
			(net "P5E_CPU1_P2_TX_DN<1>")
		)
	)
	(footprint ""
		(layer "F.Cu")
		(at 444.598552 -25.477978)
		(property "Reference" "PC2160"
			(at 0 0 0)
			(layer "F.SilkS")
			(hide yes)
			(effects
				(font
					(size 1.27 1.27)
				)
			)
		)
		(property "Value" ""
			(at 0 0 0)
			(layer "F.Fab")
			(effects
				(font
					(size 1.27 1.27)
				)
			)
		)
		(duplicate_pad_numbers_are_jumpers no)
		(fp_line
			(start -0.7874 -0.4064)
			(end 0.7874 -0.4064)
			(stroke
				(width 0.1524)
				(type default)
			)
			(layer "F.SilkS")
		)
		(fp_line
			(start -0.7874 0.4064)
			(end -0.7874 -0.4064)
			(stroke
				(width 0.1524)
				(type default)
			)
			(layer "F.SilkS")
		)
		(fp_line
			(start 0.7874 -0.4064)
			(end 0.7874 0.4064)
			(stroke
				(width 0.1524)
				(type default)
			)
			(layer "F.SilkS")
		)
		(fp_line
			(start 0.7874 0.4064)
			(end -0.7874 0.4064)
			(stroke
				(width 0.1524)
				(type default)
			)
			(layer "F.SilkS")
		)
		(fp_line
			(start -0.67945 -0.305054)
			(end -0.12065 -0.305054)
			(stroke
				(width 0.1)
				(type default)
			)
			(layer "F.Fab")
		)
		(fp_line
			(start -0.67945 0.3048)
			(end -0.67945 -0.305054)
			(stroke
				(width 0.1)
				(type default)
			)
			(layer "F.Fab")
		)
		(fp_line
			(start -0.12065 -0.305054)
			(end -0.12065 -0.2794)
			(stroke
				(width 0.1)
				(type default)
			)
			(layer "F.Fab")
		)
		(fp_line
			(start -0.12065 -0.2794)
			(end 0.12065 -0.2794)
			(stroke
				(width 0.1)
				(type default)
			)
			(layer "F.Fab")
		)
		(fp_line
			(start -0.12065 0.2794)
			(end -0.12065 0.3048)
			(stroke
				(width 0.1)
				(type default)
			)
			(layer "F.Fab")
		)
		(fp_line
			(start -0.12065 0.3048)
			(end -0.67945 0.3048)
			(stroke
				(width 0.1)
				(type default)
			)
			(layer "F.Fab")
		)
		(fp_line
			(start 0.120396 0.2794)
			(end -0.12065 0.2794)
			(stroke
				(width 0.1)
				(type default)
			)
			(layer "F.Fab")
		)
		(fp_line
			(start 0.120396 0.3048)
			(end 0.120396 0.2794)
			(stroke
				(width 0.1)
				(type default)
			)
			(layer "F.Fab")
		)
		(fp_line
			(start 0.12065 -0.3048)
			(end 0.67945 -0.3048)
			(stroke
				(width 0.1)
				(type default)
			)
			(layer "F.Fab")
		)
		(fp_line
			(start 0.12065 -0.2794)
			(end 0.12065 -0.3048)
			(stroke
				(width 0.1)
				(type default)
			)
			(layer "F.Fab")
		)
		(fp_line
			(start 0.67945 -0.3048)
			(end 0.67945 0.3048)
			(stroke
				(width 0.1)
				(type default)
			)
			(layer "F.Fab")
		)
		(fp_line
			(start 0.67945 0.3048)
			(end 0.120396 0.3048)
			(stroke
				(width 0.1)
				(type default)
			)
			(layer "F.Fab")
		)
		(pad "1" smd circle
			(at -0.40005 0)
			(size 0 0)
			(layers "F.Cu" "F.Mask" "F.Paste")
			(net "P12V_OCP_SFF")
		)
		(pad "2" smd circle
			(at 0.40005 0)
			(size 0 0)
			(layers "F.Cu" "F.Mask" "F.Paste")
			(net "GND")
		)
	)
)
